FILE_TYPE = MACRO_DRAWING;
SET COLOR_WIRE YELLOW;
SET COLOR_PROP ORANGE;
SET COLOR_DOT WHITE;
SET COLOR_ARC YELLOW;
SET COLOR_BODY GREEN;
SET COLOR_NOTE PURPLE;
SET PROP_DISPLAY VALUE;
SET PAGE_NUMBER P15;
FORCEADD SOCKET4677_AZIF0045P001C01CS..3
(200 2475);
FORCEPROP 1 LAST PART_NUMBER DGA^7000023
J 0
(-850 4075);
DISPLAY 0.723404 (-850 4075);
PAINT GREEN (-850 4075);
DISPLAY INVISIBLE (-850 4075);
FORCEPROP 2 LAST PART_TYPE SMLF
J 0
(-850 4250);
DISPLAY 1.021277 (-850 4250);
FORCEPROP 1 LAST MATERIAL IO
J 0
(-850 4000);
DISPLAY 0.723404 (-850 4000);
PAINT GREEN (-850 4000);
FORCEPROP 2 LAST VALUE SOCKET4677_AZIF0045-P001C01CS
J 0
(-850 4200);
DISPLAY 1.021277 (-850 4200);
FORCEPROP 1 LAST $LOCATION U2
J 0
(-850 4150);
DISPLAY 0.723404 (-850 4150);
PAINT GREEN (-850 4150);
FORCEPROP 0 LASTPIN (-1000 3800) $PN CV20
J 2
(-1010 3810);
DISPLAY 0.680851 (-1010 3810);
PAINT MONO (-1010 3810);
FORCEPROP 0 LASTPIN (-1000 1450) $PN CE64
J 2
(-1010 1460);
DISPLAY 0.680851 (-1010 1460);
PAINT MONO (-1010 1460);
FORCEPROP 0 LASTPIN (-1000 1400) $PN CD63
J 2
(-1010 1410);
DISPLAY 0.680851 (-1010 1410);
PAINT MONO (-1010 1410);
FORCEPROP 0 LASTPIN (1400 2050) $PN CY20
J 0
(1410 2060);
DISPLAY 0.680851 (1410 2060);
PAINT MONO (1410 2060);
FORCEPROP 0 LASTPIN (1400 3050) $PN BA70
J 0
(1410 3060);
DISPLAY 0.680851 (1410 3060);
PAINT MONO (1410 3060);
FORCEPROP 0 LASTPIN (1400 3000) $PN AV71
J 0
(1410 3010);
DISPLAY 0.680851 (1410 3010);
PAINT MONO (1410 3010);
FORCEPROP 0 LASTPIN (-1000 2850) $PN AU62
J 2
(-1010 2860);
DISPLAY 0.680851 (-1010 2860);
PAINT MONO (-1010 2860);
FORCEPROP 0 LASTPIN (-1000 1700) $PN AU64
J 2
(-1010 1710);
DISPLAY 0.680851 (-1010 1710);
PAINT MONO (-1010 1710);
FORCEPROP 0 LASTPIN (-1000 2400) $PN AV63
J 2
(-1010 2410);
DISPLAY 0.680851 (-1010 2410);
PAINT MONO (-1010 2410);
FORCEPROP 0 LASTPIN (1400 3700) $PN AW19
J 0
(1410 3710);
DISPLAY 0.680851 (1410 3710);
PAINT MONO (1410 3710);
FORCEPROP 0 LASTPIN (-1000 2300) $PN AW64
J 2
(-1010 2310);
DISPLAY 0.680851 (-1010 2310);
PAINT MONO (-1010 2310);
FORCEPROP 0 LASTPIN (1400 2850) $PN AW70
J 0
(1410 2860);
DISPLAY 0.680851 (1410 2860);
PAINT MONO (1410 2860);
FORCEPROP 0 LASTPIN (-1000 2700) $PN AY61
J 2
(-1010 2710);
DISPLAY 0.680851 (-1010 2710);
PAINT MONO (-1010 2710);
FORCEPROP 0 LASTPIN (-1000 2800) $PN AY67
J 2
(-1010 2810);
DISPLAY 0.680851 (-1010 2810);
PAINT MONO (-1010 2810);
FORCEPROP 0 LASTPIN (-1000 2350) $PN BA62
J 2
(-1010 2360);
DISPLAY 0.680851 (-1010 2360);
PAINT MONO (-1010 2360);
FORCEPROP 0 LASTPIN (-1000 2750) $PN BA66
J 2
(-1010 2760);
DISPLAY 0.680851 (-1010 2760);
PAINT MONO (-1010 2760);
FORCEPROP 0 LASTPIN (-1000 2550) $PN BA68
J 2
(-1010 2560);
DISPLAY 0.680851 (-1010 2560);
PAINT MONO (-1010 2560);
FORCEPROP 0 LASTPIN (-1000 2450) $PN BB61
J 2
(-1010 2460);
DISPLAY 0.680851 (-1010 2460);
PAINT MONO (-1010 2460);
FORCEPROP 0 LASTPIN (-1000 2900) $PN BB67
J 2
(-1010 2910);
DISPLAY 0.680851 (-1010 2910);
PAINT MONO (-1010 2910);
FORCEPROP 0 LASTPIN (1400 2150) $PN BC25
J 0
(1410 2160);
DISPLAY 0.680851 (1410 2160);
PAINT MONO (1410 2160);
FORCEPROP 0 LASTPIN (-1000 2500) $PN BC64
J 2
(-1010 2510);
DISPLAY 0.680851 (-1010 2510);
PAINT MONO (-1010 2510);
FORCEPROP 0 LASTPIN (-1000 2200) $PN BD61
J 2
(-1010 2210);
DISPLAY 0.680851 (-1010 2210);
PAINT MONO (-1010 2210);
FORCEPROP 0 LASTPIN (-1000 1550) $PN BD63
J 2
(-1010 1560);
DISPLAY 0.680851 (-1010 1560);
PAINT MONO (-1010 1560);
FORCEPROP 0 LASTPIN (-1000 2250) $PN BD65
J 2
(-1010 2260);
DISPLAY 0.680851 (-1010 2260);
PAINT MONO (-1010 2260);
FORCEPROP 0 LASTPIN (1400 2200) $PN BE25
J 0
(1410 2210);
DISPLAY 0.680851 (1410 2210);
PAINT MONO (1410 2210);
FORCEPROP 0 LASTPIN (-1000 1600) $PN BE62
J 2
(-1010 1610);
DISPLAY 0.680851 (-1010 1610);
PAINT MONO (-1010 1610);
FORCEPROP 0 LASTPIN (-1000 1900) $PN BF65
J 2
(-1010 1910);
DISPLAY 0.680851 (-1010 1910);
PAINT MONO (-1010 1910);
FORCEPROP 0 LASTPIN (-1000 1950) $PN BG62
J 2
(-1010 1960);
DISPLAY 0.680851 (-1010 1960);
PAINT MONO (-1010 1960);
FORCEPROP 0 LASTPIN (-1000 2050) $PN BG64
J 2
(-1010 2060);
DISPLAY 0.680851 (-1010 2060);
PAINT MONO (-1010 2060);
FORCEPROP 0 LASTPIN (-1000 2000) $PN BH63
J 2
(-1010 2010);
DISPLAY 0.680851 (-1010 2010);
PAINT MONO (-1010 2010);
FORCEPROP 0 LASTPIN (-1000 1850) $PN BH65
J 2
(-1010 1860);
DISPLAY 0.680851 (-1010 1860);
PAINT MONO (-1010 1860);
FORCEPROP 0 LASTPIN (-1000 1750) $PN BJ64
J 2
(-1010 1760);
DISPLAY 0.680851 (-1010 1760);
PAINT MONO (-1010 1760);
FORCEPROP 0 LASTPIN (-1000 1800) $PN BK63
J 2
(-1010 1810);
DISPLAY 0.680851 (-1010 1810);
PAINT MONO (-1010 1810);
FORCEPROP 0 LASTPIN (-1000 1650) $PN BM63
J 2
(-1010 1660);
DISPLAY 0.680851 (-1010 1660);
PAINT MONO (-1010 1660);
FORCEPROP 0 LASTPIN (1400 2550) $PN CD65
J 0
(1410 2560);
DISPLAY 0.680851 (1410 2560);
PAINT MONO (1410 2560);
FORCEPROP 0 LASTPIN (1400 2600) $PN CF63
J 0
(1410 2610);
DISPLAY 0.680851 (1410 2610);
PAINT MONO (1410 2610);
FORCEPROP 0 LASTPIN (1400 2700) $PN CF65
J 0
(1410 2710);
DISPLAY 0.680851 (1410 2710);
PAINT MONO (1410 2710);
FORCEPROP 0 LASTPIN (1400 2750) $PN CH63
J 0
(1410 2760);
DISPLAY 0.680851 (1410 2760);
PAINT MONO (1410 2760);
FORCEPROP 0 LASTPIN (-1000 3750) $PN CH71
J 2
(-1010 3760);
DISPLAY 0.680851 (-1010 3760);
PAINT MONO (-1010 3760);
FORCEPROP 0 LASTPIN (-1000 3500) $PN CJ21
J 2
(-1010 3510);
DISPLAY 0.680851 (-1010 3510);
PAINT MONO (-1010 3510);
FORCEPROP 0 LASTPIN (1400 2350) $PN CJ23
J 0
(1410 2360);
DISPLAY 0.680851 (1410 2360);
PAINT MONO (1410 2360);
FORCEPROP 0 LASTPIN (1400 2300) $PN CJ25
J 0
(1410 2310);
DISPLAY 0.680851 (1410 2310);
PAINT MONO (1410 2310);
FORCEPROP 0 LASTPIN (1400 2650) $PN CJ66
J 0
(1410 2660);
DISPLAY 0.680851 (1410 2660);
PAINT MONO (1410 2660);
FORCEPROP 0 LASTPIN (1400 3750) $PN CK22
J 0
(1410 3760);
DISPLAY 0.680851 (1410 3760);
PAINT MONO (1410 3760);
FORCEPROP 0 LASTPIN (-1000 3550) $PN CK24
J 2
(-1010 3560);
DISPLAY 0.680851 (-1010 3560);
PAINT MONO (-1010 3560);
FORCEPROP 0 LASTPIN (1400 2400) $PN CL23
J 0
(1410 2410);
DISPLAY 0.680851 (1410 2410);
PAINT MONO (1410 2410);
FORCEPROP 0 LASTPIN (1400 1800) $PN CL66
J 0
(1410 1810);
DISPLAY 0.680851 (1410 1810);
PAINT MONO (1410 1810);
FORCEPROP 0 LASTPIN (-1000 3650) $PN CN21
J 2
(-1010 3660);
DISPLAY 0.680851 (-1010 3660);
PAINT MONO (-1010 3660);
FORCEPROP 0 LASTPIN (-1000 3000) $PN CN23
J 2
(-1010 3010);
DISPLAY 0.680851 (-1010 3010);
PAINT MONO (-1010 3010);
FORCEPROP 0 LASTPIN (-1000 3250) $PN CP22
J 2
(-1010 3260);
DISPLAY 0.680851 (-1010 3260);
PAINT MONO (-1010 3260);
FORCEPROP 0 LASTPIN (-1000 3050) $PN CP24
J 2
(-1010 3060);
DISPLAY 0.680851 (-1010 3060);
PAINT MONO (-1010 3060);
FORCEPROP 0 LASTPIN (-1000 3600) $PN CR21
J 2
(-1010 3610);
DISPLAY 0.680851 (-1010 3610);
PAINT MONO (-1010 3610);
FORCEPROP 0 LASTPIN (-1000 3400) $PN CT22
J 2
(-1010 3410);
DISPLAY 0.680851 (-1010 3410);
PAINT MONO (-1010 3410);
FORCEPROP 0 LASTPIN (-1000 3100) $PN CT24
J 2
(-1010 3110);
DISPLAY 0.680851 (-1010 3110);
PAINT MONO (-1010 3110);
FORCEPROP 0 LASTPIN (-1000 3300) $PN CV22
J 2
(-1010 3310);
DISPLAY 0.680851 (-1010 3310);
PAINT MONO (-1010 3310);
FORCEPROP 0 LASTPIN (-1000 1250) $PN CV69
J 2
(-1010 1260);
DISPLAY 0.680851 (-1010 1260);
PAINT MONO (-1010 1260);
FORCEPROP 0 LASTPIN (-1000 1200) $PN CV71
J 2
(-1010 1210);
DISPLAY 0.680851 (-1010 1210);
PAINT MONO (-1010 1210);
FORCEPROP 0 LASTPIN (-1000 3700) $PN CW21
J 2
(-1010 3710);
DISPLAY 0.680851 (-1010 3710);
PAINT MONO (-1010 3710);
FORCEPROP 0 LASTPIN (-1000 1300) $PN CY69
J 2
(-1010 1310);
DISPLAY 0.680851 (-1010 1310);
PAINT MONO (-1010 1310);
FORCEPROP 0 LASTPIN (-1000 1150) $PN CY71
J 2
(-1010 1160);
DISPLAY 0.680851 (-1010 1160);
PAINT MONO (-1010 1160);
FORCEPROP 0 LASTPIN (1400 1950) $PN CJ64
J 0
(1410 1960);
DISPLAY 0.680851 (1410 1960);
PAINT MONO (1410 1960);
FORCEPROP 0 LASTPIN (1400 1900) $PN CK65
J 0
(1410 1910);
DISPLAY 0.680851 (1410 1910);
PAINT MONO (1410 1910);
FORCEPROP 0 LASTPIN (1400 2000) $PN CH65
J 0
(1410 2010);
DISPLAY 0.680851 (1410 2010);
PAINT MONO (1410 2010);
FORCEPROP 0 LASTPIN (-1000 3350) $PN CY22
J 2
(-1010 3360);
DISPLAY 0.680851 (-1010 3360);
PAINT MONO (-1010 3360);
FORCEPROP 0 LASTPIN (1400 3800) $PN CF61
J 0
(1410 3810);
DISPLAY 0.680851 (1410 3810);
PAINT MONO (1410 3810);
FORCEPROP 0 LASTPIN (1400 2950) $PN AV69
J 0
(1410 2960);
DISPLAY 0.680851 (1410 2960);
PAINT MONO (1410 2960);
FORCEPROP 0 LASTPIN (1400 2900) $PN AY69
J 0
(1410 2910);
DISPLAY 0.680851 (1410 2910);
PAINT MONO (1410 2910);
FORCEPROP 2 LAST CDS_LIB pure_quanta
J 0
(200 2475);
DISPLAY INVISIBLE (200 2475);
FORCEPROP 1 LAST NEEDS_NO_SIZE TRUE
J 0
(200 2475);
DISPLAY 0.723404 (200 2475);
PAINT GREEN (200 2475);
DISPLAY INVISIBLE (200 2475);
FORCEPROP 1 LAST CDS_LMAN_SYM_OUTLINE -1050,1500,1050,-1450
J 0
(200 2475);
DISPLAY 0.468085 (200 2475);
PAINT GREEN (200 2475);
DISPLAY INVISIBLE (200 2475);
FORCEPROP 2 LAST CDS_LOCATION U2
J 0
(-850 4300);
DISPLAY 1.021277 (-850 4300);
DISPLAY INVISIBLE (-850 4300);
FORCEPROP 0 LAST $SEC 3
J 0
(-850 4300);
DISPLAY 0.680851 (-850 4300);
PAINT MONO (-850 4300);
DISPLAY INVISIBLE (-850 4300);
FORCEPROP 2 LAST CDS_SEC 3
J 0
(-850 4300);
DISPLAY 1.021277 (-850 4300);
DISPLAY INVISIBLE (-850 4300);
FORCEPROP 1 LAST PATH I1
J 0
(200 2475);
DISPLAY 0.723404 (200 2475);
PAINT GREEN (200 2475);
DISPLAY INVISIBLE (200 2475);
FORCEADD OFFPAGE..2
(3125 2850);
FORCEPROP 2 LAST $XR0 120 
J 0
(3314 2850);
DISPLAY 0.638298 (3314 2850);
PAINT MONO (3314 2850);
FORCEPROP 2 LAST CDS_LIB standard
J 0
(3125 2850);
PAINT MONO (3125 2850);
DISPLAY INVISIBLE (3125 2850);
FORCEPROP 1 LAST OFFPAGE TRUE
J 0
(3450 2725);
DISPLAY 1.170213 (3450 2725);
PAINT GREEN (3450 2725);
DISPLAY INVISIBLE (3450 2725);
FORCEPROP 1 LAST COMMENT_BODY TRUE
J 0
(3080 2755);
DISPLAY 1.170213 (3080 2755);
PAINT GREEN (3080 2755);
DISPLAY INVISIBLE (3080 2755);
FORCEPROP 2 LAST PATH I10
J 0
(3300 2925);
DISPLAY 1.021277 (3300 2925);
DISPLAY INVISIBLE (3300 2925);
FORCEADD OFFPAGE..4
(3125 1900);
FORCEPROP 2 LAST $XR0 80 
J 0
(3311 1900);
DISPLAY 0.638298 (3311 1900);
PAINT MONO (3311 1900);
FORCEPROP 2 LAST CDS_LIB standard
J 0
(3125 1900);
PAINT MONO (3125 1900);
DISPLAY INVISIBLE (3125 1900);
FORCEPROP 1 LAST OFFPAGE TRUE
J 0
(3450 1775);
DISPLAY 1.170213 (3450 1775);
PAINT GREEN (3450 1775);
DISPLAY INVISIBLE (3450 1775);
FORCEPROP 1 LAST COMMENT_BODY TRUE
J 0
(3100 1800);
DISPLAY 1.170213 (3100 1800);
PAINT GREEN (3100 1800);
DISPLAY INVISIBLE (3100 1800);
FORCEPROP 2 LAST PATH I11
J 0
(3300 1975);
DISPLAY 1.021277 (3300 1975);
DISPLAY INVISIBLE (3300 1975);
FORCEADD OFFPAGE..4
(3125 1950);
FORCEPROP 2 LAST $XR0 80 
J 0
(3311 1950);
DISPLAY 0.638298 (3311 1950);
PAINT MONO (3311 1950);
FORCEPROP 2 LAST CDS_LIB standard
J 0
(3125 1950);
PAINT MONO (3125 1950);
DISPLAY INVISIBLE (3125 1950);
FORCEPROP 1 LAST OFFPAGE TRUE
J 0
(3450 1825);
DISPLAY 1.170213 (3450 1825);
PAINT GREEN (3450 1825);
DISPLAY INVISIBLE (3450 1825);
FORCEPROP 1 LAST COMMENT_BODY TRUE
J 0
(3100 1850);
DISPLAY 1.170213 (3100 1850);
PAINT GREEN (3100 1850);
DISPLAY INVISIBLE (3100 1850);
FORCEPROP 2 LAST PATH I13
J 0
(3300 2025);
DISPLAY 1.021277 (3300 2025);
DISPLAY INVISIBLE (3300 2025);
FORCEADD OFFPAGE..4
(3125 2000);
FORCEPROP 2 LAST $XR0 80 
J 0
(3311 2000);
DISPLAY 0.638298 (3311 2000);
PAINT MONO (3311 2000);
FORCEPROP 2 LAST CDS_LIB standard
J 0
(3125 2000);
PAINT MONO (3125 2000);
DISPLAY INVISIBLE (3125 2000);
FORCEPROP 1 LAST OFFPAGE TRUE
J 0
(3450 1875);
DISPLAY 1.170213 (3450 1875);
PAINT GREEN (3450 1875);
DISPLAY INVISIBLE (3450 1875);
FORCEPROP 1 LAST COMMENT_BODY TRUE
J 0
(3100 1900);
DISPLAY 1.170213 (3100 1900);
PAINT GREEN (3100 1900);
DISPLAY INVISIBLE (3100 1900);
FORCEPROP 2 LAST PATH I14
J 0
(3300 2075);
DISPLAY 1.021277 (3300 2075);
DISPLAY INVISIBLE (3300 2075);
FORCEADD OFFPAGE..2
(3125 2050);
FORCEPROP 2 LAST $XR1 213 
J 0
(3404 2050);
DISPLAY 0.638298 (3404 2050);
PAINT MONO (3404 2050);
FORCEPROP 2 LAST $XR0 80 
J 0
(3314 2050);
DISPLAY 0.638298 (3314 2050);
PAINT MONO (3314 2050);
FORCEPROP 2 LAST CDS_LIB standard
J 0
(3125 2050);
PAINT MONO (3125 2050);
DISPLAY INVISIBLE (3125 2050);
FORCEPROP 1 LAST OFFPAGE TRUE
J 0
(3450 1925);
DISPLAY 1.170213 (3450 1925);
PAINT GREEN (3450 1925);
DISPLAY INVISIBLE (3450 1925);
FORCEPROP 1 LAST COMMENT_BODY TRUE
J 0
(3080 1955);
DISPLAY 1.170213 (3080 1955);
PAINT GREEN (3080 1955);
DISPLAY INVISIBLE (3080 1955);
FORCEPROP 2 LAST PATH I15
J 0
(3325 2100);
DISPLAY 1.021277 (3325 2100);
DISPLAY INVISIBLE (3325 2100);
FORCEADD OFFPAGE..1
(-2725 3350);
FORCEPROP 2 LAST $XR0 43 
J 0
(-2946 3350);
DISPLAY 0.638298 (-2946 3350);
PAINT MONO (-2946 3350);
FORCEPROP 2 LAST CDS_LIB standard
J 0
(-2725 3350);
PAINT MONO (-2725 3350);
DISPLAY INVISIBLE (-2725 3350);
FORCEPROP 1 LAST OFFPAGE TRUE
J 0
(-2400 3225);
DISPLAY 0.872340 (-2400 3225);
DISPLAY INVISIBLE (-2400 3225);
FORCEPROP 1 LAST COMMENT_BODY TRUE
J 0
(-2600 3250);
DISPLAY 0.872340 (-2600 3250);
PAINT GREEN (-2600 3250);
DISPLAY INVISIBLE (-2600 3250);
FORCEPROP 2 LAST PATH I25
J 0
(-3000 3400);
DISPLAY 1.021277 (-3000 3400);
DISPLAY INVISIBLE (-3000 3400);
FORCEADD OFFPAGE..1
(-2725 3800);
FORCEPROP 2 LAST $XR0 43 
J 0
(-2946 3800);
DISPLAY 0.638298 (-2946 3800);
PAINT MONO (-2946 3800);
FORCEPROP 2 LAST CDS_LIB standard
J 0
(-2725 3800);
PAINT MONO (-2725 3800);
DISPLAY INVISIBLE (-2725 3800);
FORCEPROP 1 LAST OFFPAGE TRUE
J 0
(-2400 3675);
DISPLAY 0.872340 (-2400 3675);
DISPLAY INVISIBLE (-2400 3675);
FORCEPROP 1 LAST COMMENT_BODY TRUE
J 0
(-2600 3700);
DISPLAY 0.872340 (-2600 3700);
PAINT GREEN (-2600 3700);
DISPLAY INVISIBLE (-2600 3700);
FORCEPROP 2 LAST PATH I3
J 0
(-2675 3875);
DISPLAY 1.021277 (-2675 3875);
DISPLAY INVISIBLE (-2675 3875);
FORCEADD OFFPAGE..4
(3125 3800);
FORCEPROP 2 LAST $XR0 120 
J 0
(3311 3800);
DISPLAY 0.638298 (3311 3800);
PAINT MONO (3311 3800);
FORCEPROP 2 LAST CDS_LIB standard
J 0
(3125 3800);
PAINT MONO (3125 3800);
DISPLAY INVISIBLE (3125 3800);
FORCEPROP 1 LAST OFFPAGE TRUE
J 0
(3450 3675);
DISPLAY 1.170213 (3450 3675);
PAINT GREEN (3450 3675);
DISPLAY INVISIBLE (3450 3675);
FORCEPROP 1 LAST COMMENT_BODY TRUE
J 0
(3100 3700);
DISPLAY 1.170213 (3100 3700);
PAINT GREEN (3100 3700);
DISPLAY INVISIBLE (3100 3700);
FORCEPROP 2 LAST PATH I31
J 0
(3325 3850);
DISPLAY 1.021277 (3325 3850);
DISPLAY INVISIBLE (3325 3850);
FORCEADD OFFPAGE..2
R 2
(-2725 1450);
FORCEPROP 2 LAST $XR0 236 
J 0
(-3010 1450);
DISPLAY 0.638298 (-3010 1450);
PAINT MONO (-3010 1450);
FORCEPROP 2 LAST CDS_LIB standard
J 0
(-2725 1450);
PAINT MONO (-2725 1450);
DISPLAY INVISIBLE (-2725 1450);
FORCEPROP 1 LAST OFFPAGE TRUE
J 2
(-3050 1325);
DISPLAY 0.872340 (-3050 1325);
DISPLAY INVISIBLE (-3050 1325);
FORCEPROP 1 LAST COMMENT_BODY TRUE
J 2
(-2680 1355);
DISPLAY 0.872340 (-2680 1355);
PAINT GREEN (-2680 1355);
DISPLAY INVISIBLE (-2680 1355);
FORCEPROP 2 LAST PATH I4
J 0
(-2675 1525);
DISPLAY 1.021277 (-2675 1525);
DISPLAY INVISIBLE (-2675 1525);
FORCEADD OFFPAGE..3
R 2
(-2725 1400);
FORCEPROP 2 LAST $XR0 236 
J 0
(-3035 1400);
DISPLAY 0.638298 (-3035 1400);
PAINT MONO (-3035 1400);
FORCEPROP 2 LAST CDS_LIB standard
J 0
(-2725 1400);
PAINT MONO (-2725 1400);
DISPLAY INVISIBLE (-2725 1400);
FORCEPROP 1 LAST OFFPAGE TRUE
J 2
(-3050 1275);
DISPLAY 0.872340 (-3050 1275);
DISPLAY INVISIBLE (-3050 1275);
FORCEPROP 1 LAST COMMENT_BODY TRUE
J 2
(-2675 1300);
DISPLAY 0.872340 (-2675 1300);
PAINT GREEN (-2675 1300);
DISPLAY INVISIBLE (-2675 1300);
FORCEPROP 2 LAST PATH I5
J 0
(-2675 1475);
DISPLAY 1.021277 (-2675 1475);
DISPLAY INVISIBLE (-2675 1475);
FORCEADD OFFPAGE..2
(3125 2950);
FORCEPROP 2 LAST $XR0 120 
J 0
(3314 2950);
DISPLAY 0.638298 (3314 2950);
PAINT MONO (3314 2950);
FORCEPROP 2 LAST CDS_LIB standard
J 0
(3125 2950);
PAINT MONO (3125 2950);
DISPLAY INVISIBLE (3125 2950);
FORCEPROP 1 LAST OFFPAGE TRUE
J 0
(3450 2825);
DISPLAY 1.170213 (3450 2825);
PAINT GREEN (3450 2825);
DISPLAY INVISIBLE (3450 2825);
FORCEPROP 1 LAST COMMENT_BODY TRUE
J 0
(3080 2855);
DISPLAY 1.170213 (3080 2855);
PAINT GREEN (3080 2855);
DISPLAY INVISIBLE (3080 2855);
FORCEPROP 2 LAST PATH I6
J 0
(3300 3025);
DISPLAY 1.021277 (3300 3025);
DISPLAY INVISIBLE (3300 3025);
FORCEADD OFFPAGE..2
(3125 3050);
FORCEPROP 2 LAST $XR0 120 
J 0
(3314 3050);
DISPLAY 0.638298 (3314 3050);
PAINT MONO (3314 3050);
FORCEPROP 2 LAST CDS_LIB standard
J 0
(3125 3050);
PAINT MONO (3125 3050);
DISPLAY INVISIBLE (3125 3050);
FORCEPROP 1 LAST OFFPAGE TRUE
J 0
(3450 2925);
DISPLAY 1.170213 (3450 2925);
PAINT GREEN (3450 2925);
DISPLAY INVISIBLE (3450 2925);
FORCEPROP 1 LAST COMMENT_BODY TRUE
J 0
(3080 2955);
DISPLAY 1.170213 (3080 2955);
PAINT GREEN (3080 2955);
DISPLAY INVISIBLE (3080 2955);
FORCEPROP 2 LAST PATH I7
J 0
(3300 3125);
DISPLAY 1.021277 (3300 3125);
DISPLAY INVISIBLE (3300 3125);
FORCEADD OFFPAGE..2
(3125 3000);
FORCEPROP 2 LAST $XR0 120 
J 0
(3314 3000);
DISPLAY 0.638298 (3314 3000);
PAINT MONO (3314 3000);
FORCEPROP 2 LAST CDS_LIB standard
J 0
(3125 3000);
PAINT MONO (3125 3000);
DISPLAY INVISIBLE (3125 3000);
FORCEPROP 1 LAST OFFPAGE TRUE
J 0
(3450 2875);
DISPLAY 1.170213 (3450 2875);
PAINT GREEN (3450 2875);
DISPLAY INVISIBLE (3450 2875);
FORCEPROP 1 LAST COMMENT_BODY TRUE
J 0
(3080 2905);
DISPLAY 1.170213 (3080 2905);
PAINT GREEN (3080 2905);
DISPLAY INVISIBLE (3080 2905);
FORCEPROP 2 LAST PATH I8
J 0
(3300 3075);
DISPLAY 1.021277 (3300 3075);
DISPLAY INVISIBLE (3300 3075);
FORCEADD OFFPAGE..2
(3125 2900);
FORCEPROP 2 LAST $XR0 120 
J 0
(3314 2900);
DISPLAY 0.638298 (3314 2900);
PAINT MONO (3314 2900);
FORCEPROP 2 LAST CDS_LIB standard
J 0
(3125 2900);
PAINT MONO (3125 2900);
DISPLAY INVISIBLE (3125 2900);
FORCEPROP 1 LAST OFFPAGE TRUE
J 0
(3450 2775);
DISPLAY 1.170213 (3450 2775);
PAINT GREEN (3450 2775);
DISPLAY INVISIBLE (3450 2775);
FORCEPROP 1 LAST COMMENT_BODY TRUE
J 0
(3080 2805);
DISPLAY 1.170213 (3080 2805);
PAINT GREEN (3080 2805);
DISPLAY INVISIBLE (3080 2805);
FORCEPROP 2 LAST PATH I9
J 0
(3300 2975);
DISPLAY 1.021277 (3300 2975);
DISPLAY INVISIBLE (3300 2975);
FORCEADD QUANTA_TITLE_BLOCK_C..1
(5000 -1650);
FORCEPROP 0 LAST CDS_CON_LAST_MODIFIED Fri Aug 25 14:00:02 2023
J 0
(3115 -1635);
PAINT MONO (3115 -1635);
DISPLAY INVISIBLE (3115 -1635);
FORCEPROP 2 LAST CUSTOM_TXT_CDS <XR_PAGE_TITLE>
J 0
(-2890 3600);
DISPLAY 0.638298 (-2890 3600);
PAINT PINK (-2890 3600);
DISPLAY INVISIBLE (-2890 3600);
FORCEPROP 2 LAST CUSTOM_TXT_CDS <CON_LAST_MODIFIED>
J 0
(3115 -1635);
DISPLAY 0.978723 (3115 -1635);
FORCEPROP 2 LAST CUSTOM_TXT_CDS <CON_PAGE_NUM> OF <CON_TOTAL_PAGES>
J 0
(4554 -1632);
DISPLAY 0.978723 (4554 -1632);
FORCEPROP 2 LAST CUSTOM_TXT_CDS <Q_REV>
J 0
(4816 -1547);
DISPLAY 1.212766 (4816 -1547);
FORCEPROP 2 LAST CUSTOM_TXT_CDS <Q_PROJ>
J 0
(2618 -1548);
DISPLAY 1.212766 (2618 -1548);
FORCEPROP 2 LAST CUSTOM_TXT_CDS <Q_NUMBER>
J 0
(3597 -1547);
DISPLAY 1.212766 (3597 -1547);
FORCEPROP 1 LAST CUSTOM_TXT_CDS <NAME_2>
J 0
(1825 -1600);
FORCEPROP 1 LAST CUSTOM_TXT_CDS <NAME_1>
J 0
(1825 -1475);
FORCEPROP 1 LAST Q_TITLE SPR CPU0 MISC:(3 OF 30)
J 0
(-4366 -1624);
DISPLAY 1.957447 (-4366 -1624);
PAINT GREEN (-4366 -1624);
FORCEPROP 1 LAST Q_DEPT 
J 1
(1237 -1601);
DISPLAY 1.957447 (1237 -1601);
PAINT GREEN (1237 -1601);
FORCEPROP 2 LAST CDS_LIB pure_quanta
J 0
(5000 -1650);
PAINT MONO (5000 -1650);
DISPLAY INVISIBLE (5000 -1650);
FORCEPROP 1 LAST CDS_LMAN_SYM_OUTLINE -9475,6775,100,-125
J 0
(5000 -1650);
DISPLAY 0.468085 (5000 -1650);
PAINT GREEN (5000 -1650);
DISPLAY INVISIBLE (5000 -1650);
FORCEPROP 2 LAST PAGE_BORDER TRUE
J 0
(-2890 3600);
DISPLAY 0.638298 (-2890 3600);
PAINT PINK (-2890 3600);
DISPLAY INVISIBLE (-2890 3600);
FORCEPROP 2 LAST CDS_XR_PAGE_TITLE CR-15 : @S9S_MB_2U_LIB.S9S_MB_2U(SCH_1):PAGE15
J 0
(-2890 3600);
DISPLAY 0.638298 (-2890 3600);
PAINT PINK (-2890 3600);
DISPLAY INVISIBLE (-2890 3600);
FORCEPROP 1 LAST COMMENT_BODY TRUE
J 0
(5012 -1663);
DISPLAY 0.978723 (5012 -1663);
PAINT GREEN (5012 -1663);
DISPLAY INVISIBLE (5012 -1663);
WIRE 16 -1 (-1000 3800)(-2675 3800);
FORCEPROP 2 LAST SIG_NAME PWRGD_PLT_AUX_CPU0_LVT3
J 0
(-2612 3809);
DISPLAY 0.680851 (-2612 3809);
PAINT WHITE (-2612 3809);
WIRE 16 -1 (3075 3750)(1400 3750);
FORCEPROP 2 LAST SIG_NAME TP_FM_IBL_SYS_RST_CPU0_N
J 0
(1659 3759);
DISPLAY 0.680851 (1659 3759);
PAINT WHITE (1659 3759);
WIRE 16 -1 (-1000 3550)(-2675 3550);
FORCEPROP 2 LAST SIG_NAME TP_CPU0_PWRBTN_N
J 0
(-2612 3559);
DISPLAY 0.680851 (-2612 3559);
PAINT WHITE (-2612 3559);
WIRE 16 -1 (3075 2400)(1400 2400);
FORCEPROP 2 LAST SIG_NAME TP_I2C_S3M_RTC_CPU0_SCL
J 0
(1659 2409);
DISPLAY 0.680851 (1659 2409);
PAINT WHITE (1659 2409);
WIRE 16 -1 (-1000 2850)(-2675 2850);
FORCEPROP 2 LAST SIG_NAME TP_SPI_IBL_CPU0_TPM_CLK
J 0
(-2612 2859);
DISPLAY 0.680851 (-2612 2859);
PAINT WHITE (-2612 2859);
WIRE 16 -1 (3075 1800)(1400 1800);
FORCEPROP 2 LAST SIG_NAME TP_CPU0_SSC_SYNC
J 0
(1659 1809);
DISPLAY 0.680851 (1659 1809);
PAINT WHITE (1659 1809);
WIRE 16 -1 (-1000 3650)(-2675 3650);
FORCEPROP 2 LAST SIG_NAME TP_IBL_SLPS4_CPU0_R_N
J 0
(-2612 3659);
DISPLAY 0.680851 (-2612 3659);
PAINT WHITE (-2612 3659);
WIRE 16 -1 (-1000 3000)(-2675 3000);
FORCEPROP 2 LAST SIG_NAME TP_FM_IBL_ADR_ACK_CPU0
J 0
(-2612 3009);
DISPLAY 0.680851 (-2612 3009);
PAINT WHITE (-2612 3009);
WIRE 16 -1 (-1000 1700)(-2675 1700);
FORCEPROP 2 LAST SIG_NAME TP_ESPI_IBL_CPU0_IO2_LVC1
J 0
(-2612 1709);
DISPLAY 0.680851 (-2612 1709);
PAINT WHITE (-2612 1709);
WIRE 16 -1 (-2675 3250)(-1000 3250);
FORCEPROP 2 LAST SIG_NAME TP_JTAG_CPU0_PLD_TDO
J 0
(-2612 3259);
DISPLAY 0.680851 (-2612 3259);
PAINT WHITE (-2612 3259);
WIRE 16 -1 (-2675 3050)(-1000 3050);
FORCEPROP 2 LAST SIG_NAME TP_FM_IBL_ADR_COMPLETE_CPU0_R
J 0
(-2612 3059);
DISPLAY 0.680851 (-2612 3059);
PAINT WHITE (-2612 3059);
WIRE 16 -1 (-1000 3600)(-2675 3600);
FORCEPROP 2 LAST SIG_NAME TP_IBL_SLPS3_CPU0_R_N
J 0
(-2612 3609);
DISPLAY 0.680851 (-2612 3609);
PAINT WHITE (-2612 3609);
WIRE 16 -1 (-2675 3400)(-1000 3400);
FORCEPROP 2 LAST SIG_NAME TP_JTAG_CPU0_PLD_TDI
J 0
(-2612 3409);
DISPLAY 0.680851 (-2612 3409);
PAINT WHITE (-2612 3409);
WIRE 16 -1 (-2675 3100)(-1000 3100);
FORCEPROP 2 LAST SIG_NAME TP_FM_IBL_ADR_TRIGGER_CPU0_R
J 0
(-2612 3109);
DISPLAY 0.680851 (-2612 3109);
PAINT WHITE (-2612 3109);
WIRE 16 -1 (-1000 3300)(-2675 3300);
FORCEPROP 2 LAST SIG_NAME TP_JTAG_CPU0_PLD_TMS
J 0
(-2612 3309);
DISPLAY 0.680851 (-2612 3309);
PAINT WHITE (-2612 3309);
WIRE 16 -1 (-1000 1250)(-2675 1250);
FORCEPROP 2 LAST SIG_NAME NC_UART_IBL_CPU0_TXD
J 0
(-2612 1259);
DISPLAY 0.680851 (-2612 1259);
PAINT WHITE (-2612 1259);
WIRE 16 -1 (-1000 1200)(-2675 1200);
FORCEPROP 2 LAST SIG_NAME NC_UART_IBL_CPU0_CTS
J 0
(-2612 1209);
DISPLAY 0.680851 (-2612 1209);
PAINT WHITE (-2612 1209);
WIRE 16 -1 (-1000 3700)(-2675 3700);
FORCEPROP 2 LAST SIG_NAME TP_IBL_SLPS5_CPU0_R_N
J 0
(-2612 3709);
DISPLAY 0.680851 (-2612 3709);
PAINT WHITE (-2612 3709);
WIRE 16 -1 (3075 2050)(1400 2050);
FORCEPROP 2 LAST SIG_NAME FM_S3M_CPU0_CPLD_CRC_ERROR
J 0
(1659 2059);
DISPLAY 0.680851 (1659 2059);
PAINT WHITE (1659 2059);
WIRE 16 -1 (-2675 3350)(-1000 3350);
FORCEPROP 2 LAST SIG_NAME PD_JTAG_CPU0_PLD_TCK
J 0
(-2612 3359);
DISPLAY 0.680851 (-2612 3359);
PAINT WHITE (-2612 3359);
WIRE 16 -1 (-1000 1300)(-2675 1300);
FORCEPROP 2 LAST SIG_NAME NC_UART_IBL_CPU0_RXD
J 0
(-2612 1309);
DISPLAY 0.680851 (-2612 1309);
PAINT WHITE (-2612 1309);
WIRE 16 -1 (-1000 1150)(-2675 1150);
FORCEPROP 2 LAST SIG_NAME NC_UART_IBL_CPU0_RTS
J 0
(-2612 1159);
DISPLAY 0.680851 (-2612 1159);
PAINT WHITE (-2612 1159);
WIRE 16 -1 (-1000 2400)(-2675 2400);
FORCEPROP 2 LAST SIG_NAME TP_SPI_S3M_CPU0_CS1_LVC1_R_N
J 0
(-2612 2409);
DISPLAY 0.680851 (-2612 2409);
PAINT WHITE (-2612 2409);
WIRE 16 -1 (3075 3700)(1400 3700);
FORCEPROP 2 LAST SIG_NAME TP_FM_IBL_WAKE_CPU0_N
J 0
(1659 3709);
DISPLAY 0.680851 (1659 3709);
PAINT WHITE (1659 3709);
WIRE 16 -1 (-2675 2300)(-1000 2300);
FORCEPROP 2 LAST SIG_NAME TP_SPI_S3M_CPU0_IO1_LVC1_R
J 0
(-2612 2309);
DISPLAY 0.680851 (-2612 2309);
PAINT WHITE (-2612 2309);
WIRE 16 -1 (-1000 2700)(-2675 2700);
FORCEPROP 2 LAST SIG_NAME TP_SPI_IBL_CPU0_TPM_IO1
J 0
(-2612 2709);
DISPLAY 0.680851 (-2612 2709);
PAINT WHITE (-2612 2709);
WIRE 16 -1 (-2675 2800)(-1000 2800);
FORCEPROP 2 LAST SIG_NAME TP_SPI_IBL_CPU0_TPM_CS0_N
J 0
(-2612 2809);
DISPLAY 0.680851 (-2612 2809);
PAINT WHITE (-2612 2809);
WIRE 16 -1 (-2675 2350)(-1000 2350);
FORCEPROP 2 LAST SIG_NAME TP_SPI_S3M_CPU0_IO0_LVC1_R
J 0
(-2612 2359);
DISPLAY 0.680851 (-2612 2359);
PAINT WHITE (-2612 2359);
WIRE 16 -1 (-2675 2750)(-1000 2750);
FORCEPROP 2 LAST SIG_NAME TP_SPI_IBL_CPU0_TPM_IO0
J 0
(-2612 2759);
DISPLAY 0.680851 (-2612 2759);
PAINT WHITE (-2612 2759);
WIRE 16 -1 (-1000 2550)(-2675 2550);
FORCEPROP 2 LAST SIG_NAME TP_SPI_S3M_CPU0_OE_LVC1_R_N
J 0
(-2612 2559);
DISPLAY 0.680851 (-2612 2559);
PAINT WHITE (-2612 2559);
WIRE 16 -1 (-2675 2450)(-1000 2450);
FORCEPROP 2 LAST SIG_NAME TP_SPI_S3M_CPU0_CS0_LVC1_R_N
J 0
(-2612 2459);
DISPLAY 0.680851 (-2612 2459);
PAINT WHITE (-2612 2459);
WIRE 16 -1 (-2675 2900)(-1000 2900);
FORCEPROP 2 LAST SIG_NAME TP_SPI_IBL_CPU0_TPM_OE_N
J 0
(-2612 2909);
DISPLAY 0.680851 (-2612 2909);
PAINT WHITE (-2612 2909);
WIRE 16 -1 (3075 2150)(1400 2150);
FORCEPROP 2 LAST SIG_NAME TP_I3C_MNG2_BMC_SW_SDA
J 0
(1659 2159);
DISPLAY 0.680851 (1659 2159);
PAINT WHITE (1659 2159);
WIRE 16 -1 (-2675 2500)(-1000 2500);
FORCEPROP 2 LAST SIG_NAME TP_SPI_S3M_CPU0_CLK_LVC1_R
J 0
(-2612 2509);
DISPLAY 0.680851 (-2612 2509);
PAINT WHITE (-2612 2509);
WIRE 16 -1 (-2675 2200)(-1000 2200);
FORCEPROP 2 LAST SIG_NAME TP_SPI_S3M_CPU0_IO3_LVC1_R
J 0
(-2612 2209);
DISPLAY 0.680851 (-2612 2209);
PAINT WHITE (-2612 2209);
WIRE 16 -1 (-2675 1550)(-1000 1550);
FORCEPROP 2 LAST SIG_NAME TP_ESPI_IBL_CPU0_ALERT1_N
J 0
(-2612 1559);
DISPLAY 0.680851 (-2612 1559);
PAINT WHITE (-2612 1559);
WIRE 16 -1 (-1000 2250)(-2675 2250);
FORCEPROP 2 LAST SIG_NAME TP_SPI_S3M_CPU0_IO2_LVC1_R
J 0
(-2612 2259);
DISPLAY 0.680851 (-2612 2259);
PAINT WHITE (-2612 2259);
WIRE 16 -1 (3075 2200)(1400 2200);
FORCEPROP 2 LAST SIG_NAME TP_I3C_MNG2_BMC_SW_SCL
J 0
(1659 2209);
DISPLAY 0.680851 (1659 2209);
PAINT WHITE (1659 2209);
WIRE 16 -1 (-2675 1600)(-1000 1600);
FORCEPROP 2 LAST SIG_NAME TP_ESPI_IBL_CPU0_ALERT0_LVC1_N
J 0
(-2612 1609);
DISPLAY 0.680851 (-2612 1609);
PAINT WHITE (-2612 1609);
WIRE 16 -1 (-2675 1900)(-1000 1900);
FORCEPROP 2 LAST SIG_NAME TP_ESPI_IBL_CPU0_CS0_LVC1_N
J 0
(-2612 1909);
DISPLAY 0.680851 (-2612 1909);
PAINT WHITE (-2612 1909);
WIRE 16 -1 (-1000 1950)(-2675 1950);
FORCEPROP 2 LAST SIG_NAME TP_CLK_66M_ESPI_IBL_CPU0_LVC1
J 0
(-2612 1959);
DISPLAY 0.680851 (-2612 1959);
PAINT WHITE (-2612 1959);
WIRE 16 -1 (-2675 2050)(-1000 2050);
FORCEPROP 2 LAST SIG_NAME TP_RST_ESPI_IBL_CPU0_LVC1_N
J 0
(-2612 2059);
DISPLAY 0.680851 (-2612 2059);
PAINT WHITE (-2612 2059);
WIRE 16 -1 (-2675 2000)(-1000 2000);
FORCEPROP 2 LAST SIG_NAME TP_ESPI_IBL_CPU0_OE_LVC1_N
J 0
(-2612 2009);
DISPLAY 0.680851 (-2612 2009);
PAINT WHITE (-2612 2009);
WIRE 16 -1 (-2675 1850)(-1000 1850);
FORCEPROP 2 LAST SIG_NAME TP_ESPI_IBL_CPU0_CS1_N
J 0
(-2612 1859);
DISPLAY 0.680851 (-2612 1859);
PAINT WHITE (-2612 1859);
WIRE 16 -1 (-2675 1750)(-1000 1750);
FORCEPROP 2 LAST SIG_NAME TP_ESPI_IBL_CPU0_IO1_LVC1
J 0
(-2612 1759);
DISPLAY 0.680851 (-2612 1759);
PAINT WHITE (-2612 1759);
WIRE 16 -1 (-1000 1800)(-2675 1800);
FORCEPROP 2 LAST SIG_NAME TP_ESPI_IBL_CPU0_IO0_LVC1
J 0
(-2612 1809);
DISPLAY 0.680851 (-2612 1809);
PAINT WHITE (-2612 1809);
WIRE 16 -1 (-2675 1650)(-1000 1650);
FORCEPROP 2 LAST SIG_NAME TP_ESPI_IBL_CPU0_IO3_LVC1
J 0
(-2612 1659);
DISPLAY 0.680851 (-2612 1659);
PAINT WHITE (-2612 1659);
WIRE 16 -1 (3075 2550)(1400 2550);
FORCEPROP 2 LAST SIG_NAME TP_SGPIO_S3M_CPU0_RST_R_N
J 0
(1659 2559);
DISPLAY 0.680851 (1659 2559);
PAINT WHITE (1659 2559);
WIRE 16 -1 (3075 3800)(1400 3800);
FORCEPROP 2 LAST SIG_NAME PUD_PCH_BOOT_MODE_CPU0
J 0
(1659 3809);
DISPLAY 0.680851 (1659 3809);
PAINT WHITE (1659 3809);
WIRE 16 -1 (3075 2600)(1400 2600);
FORCEPROP 2 LAST SIG_NAME TP_SGPIO_S3M_CPU0_GSXCLK_R
J 0
(1659 2609);
DISPLAY 0.680851 (1659 2609);
PAINT WHITE (1659 2609);
WIRE 16 -1 (3075 2700)(1400 2700);
FORCEPROP 2 LAST SIG_NAME TP_SGPIO_S3M_CPU0_GSXDOUT_R
J 0
(1659 2709);
DISPLAY 0.680851 (1659 2709);
PAINT WHITE (1659 2709);
WIRE 16 -1 (3075 2750)(1400 2750);
FORCEPROP 2 LAST SIG_NAME TP_SGPIO_S3M_CPU0_GSXDIN
J 0
(1659 2759);
DISPLAY 0.680851 (1659 2759);
PAINT WHITE (1659 2759);
WIRE 16 -1 (-1000 3750)(-2675 3750);
FORCEPROP 2 LAST SIG_NAME TP_PWRGD_S0_PWROK_CPU0_LVC1
J 0
(-2612 3759);
DISPLAY 0.680851 (-2612 3759);
PAINT WHITE (-2612 3759);
WIRE 16 -1 (-1000 3500)(-2675 3500);
FORCEPROP 2 LAST SIG_NAME TP_IBL_GRST_WARN_PLD_R_N
J 0
(-2612 3509);
DISPLAY 0.680851 (-2612 3509);
PAINT WHITE (-2612 3509);
WIRE 16 -1 (3075 2350)(1400 2350);
FORCEPROP 2 LAST SIG_NAME TP_I2C_S3M_RTC_CPU0_SDA
J 0
(1659 2359);
DISPLAY 0.680851 (1659 2359);
PAINT WHITE (1659 2359);
WIRE 16 -1 (3075 2300)(1400 2300);
FORCEPROP 2 LAST SIG_NAME TP_I2C_S3M_RTC_CPU0_ALERT_N
J 0
(1659 2309);
DISPLAY 0.680851 (1659 2309);
PAINT WHITE (1659 2309);
WIRE 16 -1 (3075 2650)(1400 2650);
FORCEPROP 2 LAST SIG_NAME TP_SGPIO_S3M_CPU0_GSXDLOAD_R
J 0
(1659 2659);
DISPLAY 0.680851 (1659 2659);
PAINT WHITE (1659 2659);
WIRE 16 -1 (3075 2850)(1400 2850);
FORCEPROP 2 LAST SIG_NAME FM_S3M_CPU0_LVC1_GPIO_4
J 0
(1659 2859);
DISPLAY 0.680851 (1659 2859);
PAINT WHITE (1659 2859);
WIRE 16 -1 (3075 2900)(1400 2900);
FORCEPROP 2 LAST SIG_NAME FM_S3M_CPU0_LVC1_GPIO_3
J 0
(1659 2909);
DISPLAY 0.680851 (1659 2909);
PAINT WHITE (1659 2909);
WIRE 16 -1 (3075 2950)(1400 2950);
FORCEPROP 2 LAST SIG_NAME FM_S3M_CPU0_LVC1_GPIO_2
J 0
(1659 2959);
DISPLAY 0.680851 (1659 2959);
PAINT WHITE (1659 2959);
WIRE 16 -1 (3075 3000)(1400 3000);
FORCEPROP 2 LAST SIG_NAME FM_S3M_CPU0_LVC1_GPIO_1
J 0
(1659 3009);
DISPLAY 0.680851 (1659 3009);
PAINT WHITE (1659 3009);
WIRE 16 -1 (3075 3050)(1400 3050);
FORCEPROP 2 LAST SIG_NAME FM_S3M_CPU0_LVC1_GPIO_0
J 0
(1659 3059);
DISPLAY 0.680851 (1659 3059);
PAINT WHITE (1659 3059);
WIRE 16 -1 (-1000 1450)(-2675 1450);
FORCEPROP 2 LAST SIG_NAME SMB_S3M_CPU0_SCL
J 0
(-2612 1459);
DISPLAY 0.680851 (-2612 1459);
PAINT WHITE (-2612 1459);
WIRE 16 -1 (-1000 1400)(-2675 1400);
FORCEPROP 2 LAST SIG_NAME SMB_S3M_CPU0_SDA
J 0
(-2612 1409);
DISPLAY 0.680851 (-2612 1409);
PAINT WHITE (-2612 1409);
WIRE 16 -1 (3075 1950)(1400 1950);
FORCEPROP 2 LAST SIG_NAME PU_S3M_CPU0_CPLD_CONFD
J 0
(1659 1959);
DISPLAY 0.680851 (1659 1959);
PAINT WHITE (1659 1959);
WIRE 16 -1 (3075 1900)(1400 1900);
FORCEPROP 2 LAST SIG_NAME FM_S3M_CPU0_CPLD_CONFIG_N
J 0
(1659 1909);
DISPLAY 0.680851 (1659 1909);
PAINT WHITE (1659 1909);
WIRE 16 -1 (3075 2000)(1400 2000);
FORCEPROP 2 LAST SIG_NAME PU_S3M_CPU0_CPLD_STATUS
J 0
(1659 2009);
DISPLAY 0.680851 (1659 2009);
PAINT WHITE (1659 2009);
FORCENOTE
CPU0 SPI FLASH
(-3425 2375) 0;
DISPLAY LEFT (-3425 2375);
DISPLAY 1.021277 (-3425 2375);
PAINT YELLOW (-3425 2375);
FORCENOTE
DEBUG PLD
(3225 2650) 0;
DISPLAY LEFT (3225 2650);
DISPLAY 1.021277 (3225 2650);
PAINT YELLOW (3225 2650);
QUIT
